(kicad_pcb
	(version 20211014)
	(generator pcbnew)
	(general
    (thickness 1.6)
  )
	(paper "A4")
	(title_block
    (title "SA800U (Snapdragon 845) Baseboard")
    (date "2023-10-19")
    (rev "1.0.3")
    (company "Antmicro Ltd.")
    (comment 1 "www.antmicro.com")
		(comment 9 "footprints 269-272 of 589")
	)
	(layers
    (0 "F.Cu" signal)
    (1 "In1.Cu" power)
    (2 "In2.Cu" signal)
    (3 "In3.Cu" signal)
    (4 "In4.Cu" power)
    (31 "B.Cu" signal)
    (32 "B.Adhes" user "B.Adhesive")
    (33 "F.Adhes" user "F.Adhesive")
    (34 "B.Paste" user)
    (35 "F.Paste" user)
    (36 "B.SilkS" user "B.Silkscreen")
    (37 "F.SilkS" user "F.Silkscreen")
    (38 "B.Mask" user)
    (39 "F.Mask" user)
    (40 "Dwgs.User" user "User.Drawings")
    (41 "Cmts.User" user "User.Comments")
    (42 "Eco1.User" user "User.Eco1")
    (43 "Eco2.User" user "User.Eco2")
    (44 "Edge.Cuts" user)
    (45 "Margin" user)
    (46 "B.CrtYd" user "B.Courtyard")
    (47 "F.CrtYd" user "F.Courtyard")
    (48 "B.Fab" user)
    (49 "F.Fab" user)
  )
	(footprint "sa800u-baseboard-hw-footprints:Conn_FFC_WE_68715014x22_ALT" locked (layer "B.Cu")
    (tedit 5D9CB84E)
    (at 105 84.75)
    (property "Author" "Antmicro")
    (property "License" "Apache-2.0")
    (property "MPN" "68715014522")
    (property "Manufacturer" "Würth Elektronik")
    (property "Sheetfile" "camera-interface.kicad_sch")
    (property "Sheetname" "Camera Interface")
    (attr smd)
    (fp_text reference "J7" (at 17.09 3.38 180) (layer "B.SilkS")
      (effects (font (size 0.7 0.7) (thickness 0.15)) (justify left bottom mirror))
    )
    (fp_text value "Conn_FFC_WE_68715014522_TWO-SIDES" (at -0.3 -3.899 180) (layer "B.Fab")
      (effects (font (size 0.7 0.7) (thickness 0.15)) (justify left bottom mirror))
    )
    (fp_text user "License: Apache-2.0" (at -15.861 -7.9 180) (layer "B.Fab") hide
      (effects (font (size 0.7 0.7) (thickness 0.15)) (justify left bottom mirror))
    )
    (fp_text user "Author: Antmicro" (at -15.861 -6.9 180) (layer "B.Fab") hide
      (effects (font (size 0.7 0.7) (thickness 0.15)) (justify left bottom mirror))
    )
    (fp_text user "${REFERENCE}" (at -15.861 -5.9 180) (layer "B.Fab") hide
      (effects (font (size 0.7 0.7) (thickness 0.15)) (justify left bottom mirror))
    )
    (fp_line (start 12.499 2.15) (end 12.499 2.976) (layer "B.SilkS") (width 0.15))
    (fp_line (start -12.5 2.15) (end -12.5 3.4) (layer "B.SilkS") (width 0.15))
    (fp_line (start 15.839 -1.29) (end 15.839 2.15) (layer "B.SilkS") (width 0.15))
    (fp_line (start -15.861 -1.298) (end -15.861 2.15) (layer "B.SilkS") (width 0.15))
    (fp_line (start -15.83 2.15) (end -12.5 2.15) (layer "B.SilkS") (width 0.15))
    (fp_line (start 12.499 1.325) (end 12.499 -1.259) (layer "B.SilkS") (width 0.15))
    (fp_line (start 12.499 -1.29) (end 15.839 -1.29) (layer "B.SilkS") (width 0.15))
    (fp_line (start -12.5 2.976) (end 12.499 2.976) (layer "B.SilkS") (width 0.15))
    (fp_line (start 15.81 2.15) (end 12.499 2.15) (layer "B.SilkS") (width 0.15))
    (fp_line (start -12.561 -1.33) (end -15.84 -1.33) (layer "B.SilkS") (width 0.15))
    (fp_line (start -12.5 1.325) (end 12.499 1.325) (layer "B.SilkS") (width 0.15))
    (fp_line (start -12.5 1.325) (end -12.5 -1.33) (layer "B.SilkS") (width 0.15))
    (fp_circle (center -12.25 3.86) (end -12.2 3.81) (layer "B.SilkS") (width 0.15) (fill solid))
    (fp_rect (start -16.201 6.001) (end 16.198 -3.548) (layer "B.CrtYd") (width 0.05) (fill none))
    (pad "1" smd roundrect locked (at -12.25 2.15) (size 0.3 1.2) (layers "B.Cu" "B.Paste" "B.Mask") (roundrect_rratio 0.25)
      (net 283 "/Camera Interface/CSI1_LN3_FFC_N") (pintype "passive"))
    (pad "2" smd roundrect locked (at -11.75 2.15) (size 0.3 1.2) (layers "B.Cu" "B.Paste" "B.Mask") (roundrect_rratio 0.25)
      (net 282 "/Camera Interface/CSI1_LN3_FFC_P") (pintype "passive"))
    (pad "3" smd roundrect locked (at -11.25 2.15) (size 0.3 1.2) (layers "B.Cu" "B.Paste" "B.Mask") (roundrect_rratio 0.25)
      (net 279 "/Camera Interface/CSI1_LN2_FFC_N") (pintype "passive"))
    (pad "4" smd roundrect locked (at -10.75 2.15) (size 0.3 1.2) (layers "B.Cu" "B.Paste" "B.Mask") (roundrect_rratio 0.25)
      (net 278 "/Camera Interface/CSI1_LN2_FFC_P") (pintype "passive"))
    (pad "5" smd roundrect locked (at -10.25 2.15) (size 0.3 1.2) (layers "B.Cu" "B.Paste" "B.Mask") (roundrect_rratio 0.25)
      (net 273 "/Camera Interface/CSI1_LN1_FFC_N") (pintype "passive"))
    (pad "6" smd roundrect locked (at -9.75 2.15) (size 0.3 1.2) (layers "B.Cu" "B.Paste" "B.Mask") (roundrect_rratio 0.25)
      (net 272 "/Camera Interface/CSI1_LN1_FFC_P") (pintype "passive"))
    (pad "7" smd roundrect locked (at -9.25 2.15) (size 0.3 1.2) (layers "B.Cu" "B.Paste" "B.Mask") (roundrect_rratio 0.25)
      (net 269 "/Camera Interface/CSI1_LN0_FFC_N") (pintype "passive"))
    (pad "8" smd roundrect locked (at -8.75 2.15) (size 0.3 1.2) (layers "B.Cu" "B.Paste" "B.Mask") (roundrect_rratio 0.25)
      (net 268 "/Camera Interface/CSI1_LN0_FFC_P") (pintype "passive"))
    (pad "9" smd roundrect locked (at -8.25 2.15) (size 0.3 1.2) (layers "B.Cu" "B.Paste" "B.Mask") (roundrect_rratio 0.25)
      (net 1 "GND") (pintype "passive"))
    (pad "10" smd roundrect locked (at -7.75 2.15) (size 0.3 1.2) (layers "B.Cu" "B.Paste" "B.Mask") (roundrect_rratio 0.25)
      (net 275 "/Camera Interface/CSI1_CLK_FFC_N") (pintype "passive"))
    (pad "11" smd roundrect locked (at -7.25 2.15) (size 0.3 1.2) (layers "B.Cu" "B.Paste" "B.Mask") (roundrect_rratio 0.25)
      (net 274 "/Camera Interface/CSI1_CLK_FFC_P") (pintype "passive"))
    (pad "12" smd roundrect locked (at -6.75 2.15) (size 0.3 1.2) (layers "B.Cu" "B.Paste" "B.Mask") (roundrect_rratio 0.25)
      (net 1 "GND") (pintype "passive"))
    (pad "13" smd roundrect locked (at -6.25 2.15) (size 0.3 1.2) (layers "B.Cu" "B.Paste" "B.Mask") (roundrect_rratio 0.25)
      (net 451 "unconnected-(J7-Pad13)") (pintype "passive+no_connect"))
    (pad "14" smd roundrect locked (at -5.75 2.15) (size 0.3 1.2) (layers "B.Cu" "B.Paste" "B.Mask") (roundrect_rratio 0.25)
      (net 450 "unconnected-(J7-Pad14)") (pintype "passive+no_connect"))
    (pad "15" smd roundrect locked (at -5.25 2.15) (size 0.3 1.2) (layers "B.Cu" "B.Paste" "B.Mask") (roundrect_rratio 0.25)
      (net 1 "GND") (pintype "passive"))
    (pad "16" smd roundrect locked (at -4.75 2.15) (size 0.3 1.2) (layers "B.Cu" "B.Paste" "B.Mask") (roundrect_rratio 0.25)
      (net 449 "unconnected-(J7-Pad16)") (pintype "passive+no_connect"))
    (pad "17" smd roundrect locked (at -4.25 2.15) (size 0.3 1.2) (layers "B.Cu" "B.Paste" "B.Mask") (roundrect_rratio 0.25)
      (net 448 "unconnected-(J7-Pad17)") (pintype "passive+no_connect"))
    (pad "18" smd roundrect locked (at -3.75 2.15) (size 0.3 1.2) (layers "B.Cu" "B.Paste" "B.Mask") (roundrect_rratio 0.25)
      (net 1 "GND") (pintype "passive"))
    (pad "19" smd roundrect locked (at -3.25 2.15) (size 0.3 1.2) (layers "B.Cu" "B.Paste" "B.Mask") (roundrect_rratio 0.25)
      (net 281 "/Camera Interface/CSI0_LN3_FFC_N") (pintype "passive"))
    (pad "20" smd roundrect locked (at -2.75 2.15) (size 0.3 1.2) (layers "B.Cu" "B.Paste" "B.Mask") (roundrect_rratio 0.25)
      (net 280 "/Camera Interface/CSI0_LN3_FFC_P") (pintype "passive"))
    (pad "21" smd roundrect locked (at -2.25 2.15) (size 0.3 1.2) (layers "B.Cu" "B.Paste" "B.Mask") (roundrect_rratio 0.25)
      (net 277 "/Camera Interface/CSI0_LN2_FFC_N") (pintype "passive"))
    (pad "22" smd roundrect locked (at -1.75 2.15) (size 0.3 1.2) (layers "B.Cu" "B.Paste" "B.Mask") (roundrect_rratio 0.25)
      (net 276 "/Camera Interface/CSI0_LN2_FFC_P") (pintype "passive"))
    (pad "23" smd roundrect locked (at -1.25 2.15) (size 0.3 1.2) (layers "B.Cu" "B.Paste" "B.Mask") (roundrect_rratio 0.25)
      (net 271 "/Camera Interface/CSI0_LN1_FFC_N") (pintype "passive"))
    (pad "24" smd roundrect locked (at -0.75 2.15) (size 0.3 1.2) (layers "B.Cu" "B.Paste" "B.Mask") (roundrect_rratio 0.25)
      (net 270 "/Camera Interface/CSI0_LN1_FFC_P") (pintype "passive"))
    (pad "25" smd roundrect locked (at -0.25 2.15) (size 0.3 1.2) (layers "B.Cu" "B.Paste" "B.Mask") (roundrect_rratio 0.25)
      (net 267 "/Camera Interface/CSI0_LN0_FFC_N") (pintype "passive"))
    (pad "26" smd roundrect locked (at 0.248 2.15) (size 0.3 1.2) (layers "B.Cu" "B.Paste" "B.Mask") (roundrect_rratio 0.25)
      (net 266 "/Camera Interface/CSI0_LN0_FFC_P") (pintype "passive"))
    (pad "27" smd roundrect locked (at 0.748 2.15) (size 0.3 1.2) (layers "B.Cu" "B.Paste" "B.Mask") (roundrect_rratio 0.25)
      (net 1 "GND") (pintype "passive"))
    (pad "28" smd roundrect locked (at 1.249 2.15) (size 0.3 1.2) (layers "B.Cu" "B.Paste" "B.Mask") (roundrect_rratio 0.25)
      (net 325 "/Camera Interface/CSI0_CLK_FFC_N") (pintype "passive"))
    (pad "29" smd roundrect locked (at 1.749 2.15) (size 0.3 1.2) (layers "B.Cu" "B.Paste" "B.Mask") (roundrect_rratio 0.25)
      (net 324 "/Camera Interface/CSI0_CLK_FFC_P") (pintype "passive"))
    (pad "30" smd roundrect locked (at 2.249 2.15) (size 0.3 1.2) (layers "B.Cu" "B.Paste" "B.Mask") (roundrect_rratio 0.25)
      (net 1 "GND") (pintype "passive"))
    (pad "31" smd roundrect locked (at 2.749 2.15) (size 0.3 1.2) (layers "B.Cu" "B.Paste" "B.Mask") (roundrect_rratio 0.25)
      (net 447 "unconnected-(J7-Pad31)") (pintype "passive+no_connect"))
    (pad "32" smd roundrect locked (at 3.249 2.15) (size 0.3 1.2) (layers "B.Cu" "B.Paste" "B.Mask") (roundrect_rratio 0.25)
      (net 14 "CAM0_PWDN") (pintype "passive"))
    (pad "33" smd roundrect locked (at 3.749 2.15) (size 0.3 1.2) (layers "B.Cu" "B.Paste" "B.Mask") (roundrect_rratio 0.25)
      (net 15 "CAM0_RST") (pintype "passive"))
    (pad "34" smd roundrect locked (at 4.248 2.15) (size 0.3 1.2) (layers "B.Cu" "B.Paste" "B.Mask") (roundrect_rratio 0.25)
      (net 16 "CAM1_PWDN") (pintype "passive"))
    (pad "35" smd roundrect locked (at 4.748 2.15) (size 0.3 1.2) (layers "B.Cu" "B.Paste" "B.Mask") (roundrect_rratio 0.25)
      (net 446 "unconnected-(J7-Pad35)") (pintype "passive+no_connect"))
    (pad "36" smd roundrect locked (at 5.248 2.15) (size 0.3 1.2) (layers "B.Cu" "B.Paste" "B.Mask") (roundrect_rratio 0.25)
      (net 445 "unconnected-(J7-Pad36)") (pintype "passive+no_connect"))
    (pad "37" smd roundrect locked (at 5.749 2.15) (size 0.3 1.2) (layers "B.Cu" "B.Paste" "B.Mask") (roundrect_rratio 0.25)
      (net 444 "unconnected-(J7-Pad37)") (pintype "passive+no_connect"))
    (pad "38" smd roundrect locked (at 6.249 2.15) (size 0.3 1.2) (layers "B.Cu" "B.Paste" "B.Mask") (roundrect_rratio 0.25)
      (net 443 "unconnected-(J7-Pad38)") (pintype "passive+no_connect"))
    (pad "39" smd roundrect locked (at 6.749 2.15) (size 0.3 1.2) (layers "B.Cu" "B.Paste" "B.Mask") (roundrect_rratio 0.25)
      (net 296 "/Camera Interface/CCI0_I2C_SDA_3V3") (pintype "passive"))
    (pad "40" smd roundrect locked (at 7.249 2.15) (size 0.3 1.2) (layers "B.Cu" "B.Paste" "B.Mask") (roundrect_rratio 0.25)
      (net 294 "/Camera Interface/CCI0_I2C_SCL_3V3") (pintype "passive"))
    (pad "41" smd roundrect locked (at 7.749 2.15) (size 0.3 1.2) (layers "B.Cu" "B.Paste" "B.Mask") (roundrect_rratio 0.25)
      (net 295 "/Camera Interface/CCI1_I2C_SDA_3V3") (pintype "passive"))
    (pad "42" smd roundrect locked (at 8.249 2.15) (size 0.3 1.2) (layers "B.Cu" "B.Paste" "B.Mask") (roundrect_rratio 0.25)
      (net 293 "/Camera Interface/CCI1_I2C_SCL_3V3") (pintype "passive"))
    (pad "43" smd roundrect locked (at 8.749 2.15) (size 0.3 1.2) (layers "B.Cu" "B.Paste" "B.Mask") (roundrect_rratio 0.25)
      (net 442 "unconnected-(J7-Pad43)") (pintype "passive+no_connect"))
    (pad "44" smd roundrect locked (at 9.249 2.15) (size 0.3 1.2) (layers "B.Cu" "B.Paste" "B.Mask") (roundrect_rratio 0.25)
      (net 441 "unconnected-(J7-Pad44)") (pintype "passive+no_connect"))
    (pad "45" smd roundrect locked (at 9.749 2.15) (size 0.3 1.2) (layers "B.Cu" "B.Paste" "B.Mask") (roundrect_rratio 0.25)
      (net 440 "unconnected-(J7-Pad45)") (pintype "passive+no_connect"))
    (pad "46" smd roundrect locked (at 10.249 2.15) (size 0.3 1.2) (layers "B.Cu" "B.Paste" "B.Mask") (roundrect_rratio 0.25)
      (net 439 "unconnected-(J7-Pad46)") (pintype "passive+no_connect"))
    (pad "47" smd roundrect locked (at 10.749 2.15) (size 0.3 1.2) (layers "B.Cu" "B.Paste" "B.Mask") (roundrect_rratio 0.25)
      (net 231 "/Camera Interface/3V3_CAM") (pintype "passive"))
    (pad "48" smd roundrect locked (at 11.249 2.15) (size 0.3 1.2) (layers "B.Cu" "B.Paste" "B.Mask") (roundrect_rratio 0.25)
      (net 231 "/Camera Interface/3V3_CAM") (pintype "passive"))
    (pad "49" smd roundrect locked (at 11.749 2.15) (size 0.3 1.2) (layers "B.Cu" "B.Paste" "B.Mask") (roundrect_rratio 0.25)
      (net 133 "5V_SYS") (pintype "passive"))
    (pad "50" smd roundrect locked (at 12.249 2.15) (size 0.3 1.2) (layers "B.Cu" "B.Paste" "B.Mask") (roundrect_rratio 0.25)
      (net 133 "5V_SYS") (pintype "passive"))
    (pad "SH1" smd roundrect locked (at -14.201 4) (size 2.7 3) (layers "B.Cu" "B.Paste" "B.Mask") (roundrect_rratio 0.05)
      (net 664 "unconnected-(J7-PadSH1)") (pinfunction "SH") (pintype "passive+no_connect"))
    (pad "SH1" smd roundrect locked (at -14.198 0.3) (size 2.7 3) (layers "B.Cu" "B.Paste" "B.Mask") (roundrect_rratio 0.05)
      (net 664 "unconnected-(J7-PadSH1)") (pinfunction "SH") (pintype "passive+no_connect"))
    (pad "SH2" smd roundrect locked (at 14.198 4) (size 2.7 3) (layers "B.Cu" "B.Paste" "B.Mask") (roundrect_rratio 0.05)
      (net 665 "unconnected-(J7-PadSH2)") (pinfunction "SH") (pintype "passive+no_connect"))
    (pad "SH2" smd roundrect locked (at 14.198 0.3) (size 2.7 3) (layers "B.Cu" "B.Paste" "B.Mask") (roundrect_rratio 0.05)
      (net 665 "unconnected-(J7-PadSH2)") (pinfunction "SH") (pintype "passive+no_connect"))
  )
	(footprint "sa800u-baseboard-hw-footprints:R_0402_1005Metric" (layer "B.Cu")
    (tedit 5FD9C158)
    (at 72.9 145.3)
    (descr "Resistor SMD 0402")
    (tags "resistor SMD 0402")
    (property "Author" "Antmicro")
    (property "License" "Apache-2.0")
    (property "MPN" "CR0402-FX-4700GLF")
    (property "Manufacturer" "Bourns")
    (property "Sheetfile" "ethernet-controller.kicad_sch")
    (property "Sheetname" "Ethernet Controller")
    (property "Tolerance" "1%")
    (property "Val" "470R")
    (attr smd)
    (fp_text reference "R13" (at 1.09 -1.55 180) (layer "B.SilkS")
      (effects (font (size 0.7 0.7) (thickness 0.15)) (justify left bottom mirror))
    )
    (fp_text value "R_470R_0402" (at 0 -1.4 180) (layer "B.Fab")
      (effects (font (size 0.7 0.7) (thickness 0.15)) (justify left bottom mirror))
    )
    (fp_text user "${REFERENCE}" (at -0.95 -3.168 180) (layer "B.Fab") hide
      (effects (font (size 0.7 0.7) (thickness 0.15)) (justify left bottom mirror))
    )
    (fp_text user "Author: Antmicro" (at -0.95 -4.169 180) (layer "B.Fab") hide
      (effects (font (size 0.7 0.7) (thickness 0.15)) (justify left bottom mirror))
    )
    (fp_text user "License: Apache-2.0" (at -0.95 -5.169 180) (layer "B.Fab") hide
      (effects (font (size 0.7 0.7) (thickness 0.15)) (justify left bottom mirror))
    )
    (fp_rect (start -0.93 0.47) (end 0.93 -0.47) (layer "B.CrtYd") (width 0.05) (fill none))
    (fp_rect (start -0.5 0.25) (end 0.5 -0.25) (layer "B.Fab") (width 0.15) (fill none))
    (pad "1" smd roundrect (at -0.485 0) (size 0.59 0.64) (layers "B.Cu" "B.Paste" "B.Mask") (roundrect_rratio 0.25)
      (net 78 "Net-(J1-Pad17)") (pintype "passive"))
    (pad "2" smd roundrect (at 0.485 0) (size 0.59 0.64) (layers "B.Cu" "B.Paste" "B.Mask") (roundrect_rratio 0.25)
      (net 177 "/Ethernet Controller/ETH_3V3") (pintype "passive"))
  )
	(footprint "sa800u-baseboard-hw-footprints:R_0402_1005Metric" (layer "B.Cu")
    (tedit 5FD9C158)
    (at 72.9 144.3)
    (descr "Resistor SMD 0402")
    (tags "resistor SMD 0402")
    (property "Author" "Antmicro")
    (property "License" "Apache-2.0")
    (property "MPN" "CR0402-FX-4700GLF")
    (property "Manufacturer" "Bourns")
    (property "Sheetfile" "ethernet-controller.kicad_sch")
    (property "Sheetname" "Ethernet Controller")
    (property "Tolerance" "1%")
    (property "Val" "470R")
    (attr smd)
    (fp_text reference "R14" (at 1.09 -1.55 180) (layer "B.SilkS")
      (effects (font (size 0.7 0.7) (thickness 0.15)) (justify left bottom mirror))
    )
    (fp_text value "R_470R_0402" (at 0 -1.4 180) (layer "B.Fab")
      (effects (font (size 0.7 0.7) (thickness 0.15)) (justify left bottom mirror))
    )
    (fp_text user "Author: Antmicro" (at -0.95 -4.169 180) (layer "B.Fab") hide
      (effects (font (size 0.7 0.7) (thickness 0.15)) (justify left bottom mirror))
    )
    (fp_text user "License: Apache-2.0" (at -0.95 -5.169 180) (layer "B.Fab") hide
      (effects (font (size 0.7 0.7) (thickness 0.15)) (justify left bottom mirror))
    )
    (fp_text user "${REFERENCE}" (at -0.95 -3.168 180) (layer "B.Fab") hide
      (effects (font (size 0.7 0.7) (thickness 0.15)) (justify left bottom mirror))
    )
    (fp_rect (start -0.93 0.47) (end 0.93 -0.47) (layer "B.CrtYd") (width 0.05) (fill none))
    (fp_rect (start -0.5 0.25) (end 0.5 -0.25) (layer "B.Fab") (width 0.15) (fill none))
    (pad "1" smd roundrect (at -0.485 0) (size 0.59 0.64) (layers "B.Cu" "B.Paste" "B.Mask") (roundrect_rratio 0.25)
      (net 77 "Net-(J1-Pad15)") (pintype "passive"))
    (pad "2" smd roundrect (at 0.485 0) (size 0.59 0.64) (layers "B.Cu" "B.Paste" "B.Mask") (roundrect_rratio 0.25)
      (net 177 "/Ethernet Controller/ETH_3V3") (pintype "passive"))
  )
	(footprint "sa800u-baseboard-hw-footprints:R_0402_1005Metric" (layer "B.Cu")
    (tedit 5FD9C158)
    (at 116.845 113.6 90)
    (descr "Resistor SMD 0402")
    (tags "resistor SMD 0402")
    (property "Author" "Antmicro")
    (property "License" "Apache-2.0")
    (property "MPN" "CR0402-FX-4701GLF")
    (property "Manufacturer" "Bourns")
    (property "Sheetfile" "hdmi-converter.kicad_sch")
    (property "Sheetname" "HDMI converter")
    (property "Tolerance" "1%")
    (property "Val" "4k7")
    (attr smd)
    (fp_text reference "R23" (at 1.12 -0.58 270) (layer "B.SilkS")
      (effects (font (size 0.7 0.7) (thickness 0.15)) (justify left bottom mirror))
    )
    (fp_text value "R_4k7_0402" (at 0 -1.4 270) (layer "B.Fab")
      (effects (font (size 0.7 0.7) (thickness 0.15)) (justify left bottom mirror))
    )
    (fp_text user "Author: Antmicro" (at -0.95 -4.169 270) (layer "B.Fab") hide
      (effects (font (size 0.7 0.7) (thickness 0.15)) (justify left bottom mirror))
    )
    (fp_text user "${REFERENCE}" (at -0.95 -3.168 270) (layer "B.Fab") hide
      (effects (font (size 0.7 0.7) (thickness 0.15)) (justify left bottom mirror))
    )
    (fp_text user "License: Apache-2.0" (at -0.95 -5.169 270) (layer "B.Fab") hide
      (effects (font (size 0.7 0.7) (thickness 0.15)) (justify left bottom mirror))
    )
    (fp_rect (start -0.93 0.47) (end 0.93 -0.47) (layer "B.CrtYd") (width 0.05) (fill none))
    (fp_rect (start -0.5 0.25) (end 0.5 -0.25) (layer "B.Fab") (width 0.15) (fill none))
    (pad "1" smd roundrect (at -0.485 0 90) (size 0.59 0.64) (layers "B.Cu" "B.Paste" "B.Mask") (roundrect_rratio 0.25)
      (net 132 "VREG_S4A_1V8") (pintype "passive"))
    (pad "2" smd roundrect (at 0.485 0 90) (size 0.59 0.64) (layers "B.Cu" "B.Paste" "B.Mask") (roundrect_rratio 0.25)
      (net 35 "LT9611_GPIO5") (pintype "passive"))
  )
)
